# T6G (Grand Teton) — schematic parts with pin connectivity, parts 4730–4885 of 8303; source: Cadence DE-HDL packaged netlist (pstxprt.dat, pstxnet.dat, pstchip.dat)

R6  Q_RES  54.9K 1% CHIP  pkg 0402LF  page 102 : 1 = PD_CHE_CPU1_DIMM_SAA ; 2 = GND
R7  Q_RES  10K 1% CHIP  pkg 0402LF  page 86 : 1 = PD_CHA_CPU0_DIMM0_SAA ; 2 = GND
R8  Q_RES  100K 1% CHIP  pkg 0402LF  page 167 : 1 = GND ; 2 = JTAG_BMC_OE
R9  Q_RES  0 5% CHIP  pkg 0402LF  page 85 : 1 = JTAG_PLD_TDI ; 2 = JTAG_SCM_PLD_TDI
R10  Q_RES  10K 1% CHIP  pkg 0402LF  page 83 : 1 = FM_I3C_CPU0_MUX0_OE_N ; 2 = GND
R11  Q_RES  10K 1% CHIP  pkg 0402LF  page 83 : 1 = FM_I3C_CPU0_MUX1_OE_N ; 2 = GND
R12  Q_RES  10K 1% CHIP  pkg 0402LF  page 83 : 1 = FM_I3C_CPU1_MUX0_OE_N ; 2 = GND
R13  Q_RES  0 5% CHIP  pkg 0402LF  page 85 : 1 = JTAG_PLD_TDO ; 2 = JTAG_SCM_PLD_TDO
R14  Q_RES  0 5% CHIP  pkg 0402LF  page 85 : 1 = JTAG_PLD_TMS ; 2 = JTAG_SCM_PLD_TMS
R15  Q_RES  0 5% CHIP  pkg 0402LF  page 85 : 1 = JTAG_PLD_TCK ; 2 = JTAG_SCM_PLD_TCK
R16  Q_RES  10K 1% CHIP  pkg 0402LF  page 83 : 1 = RST_CPU0_PERST0_N ; 2 = GND
R17  Q_RES  10K 1% CHIP  pkg 0402LF  page 83 : 1 = RST_CPU0_PERST1_N ; 2 = GND
R18  Q_RES  10K 1% CHIP  pkg 0402LF  page 83 : 1 = RST_CPU1_PERST0_N ; 2 = GND
R19  Q_RES  10K 1% CHIP  pkg 0402LF  page 83 : 1 = RST_CPU1_PERST1_N ; 2 = GND
R20  Q_RES  10K 1% CHIP  pkg 0402LF  page 77 : 1 = P3V3_AUX ; 2 = SPI_CPU0_LVC3_SCM_CLK
R21  Q_RES  1K 1% EMPTY  pkg 0402LF  page 77 : 1 = P3V3_AUX ; 2 = SPI_CPU0_LVC3_SCM_D0
R22  Q_RES  100 1% CHIP  pkg 0402LF  page 167 : 1 = P1V8_AUX ; 2 = PU_BIOS_USB_RECOVERY
R23  Q_RES  33 5% CHIP  pkg 0402LF  page 80 : 1 = P3V3_OCP_SFF_EN ; 2 = P3V3_OCP_SFF_EN_R
R24  Q_RES  4.7K 5% EMPTY  pkg 0402LF  page 238 : 1 = P3V3_AUX ; 2 = SMB_CPU_FRU_3V3AUX_SDA
R25  Q_RES  10K 1% CHIP  pkg 0402LF  page 83 : 1 = FM_I3C_CPU1_MUX1_OE_N ; 2 = GND
R26  Q_RES  4.7K 5% EMPTY  pkg 0402LF  page 238 : 1 = P3V3_AUX ; 2 = SMB_FRU_3V3AUX_R1_SCL
R27  Q_RES  0 5% CHIP  pkg 0402LF  page 28 : 1 = SMB_CPU0_2_R_SCL ; 2 = SMB_CPU0_2_SCL
R28  Q_RES  0 5% CHIP  pkg 0402LF  page 28 : 1 = SMB_CPU0_2_R_SDA ; 2 = SMB_CPU0_2_SDA
R29  Q_RES  0 5% CHIP  pkg 0402LF  page 28 : 1 = SMB_CPU0_3_R_SCL ; 2 = SMB_CPU0_3_SCL
R30  Q_RES  0 5% CHIP  pkg 0402LF  page 28 : 1 = SMB_CPU0_3_R_SDA ; 2 = SMB_CPU0_3_SDA
R31  Q_RES  4.7K 1% EMPTY  pkg 0402LF  page 131 : 1 = P3V3_OCP_SFF ; 2 = OCP_SFF_ID0
R32  Q_RES  4.7K 1% CHIP  pkg 0402LF  page 131 : 1 = OCP_SFF_ID0 ; 2 = GND
R33  Q_RES  4.7K 1% EMPTY  pkg 0402LF  page 131 : 1 = P3V3_OCP_SFF ; 2 = OCP_SFF_ID1
R34  Q_RES  4.7K 1% CHIP  pkg 0402LF  page 131 : 1 = OCP_SFF_ID1 ; 2 = GND
R35  Q_RES  10K 1% CHIP  pkg 0402LF  page 92 : 1 = PD_CHG_CPU0_DIMM0_SAA ; 2 = GND
R36  Q_RES  10K 1% CHIP  pkg 0402LF  page 98 : 1 = PD_CHA_CPU1_DIMM0_SAA ; 2 = GND
R37  Q_RES  10K 1% CHIP  pkg 0402LF  page 104 : 1 = PD_CHG_CPU1_DIMM0_SAA ; 2 = GND
R38  Q_RES  0 5% CHIP  pkg 0402LF  page 131 : 1 = OCP_SFF_MAIN_PWR_EN ; 2 = OCP_SFF_MAIN_PWR_EN_R
R39  Q_RES  0 5% CHIP  pkg 0402LF  page 131 : 1 = OCP_SFF_ISO_BIF0_EN ; 2 = OCP_SFF_BIF0_R_N
R40  Q_RES  0 5% CHIP  pkg 0402LF  page 131 : 1 = OCP_SFF_ISO_BIF1_EN ; 2 = OCP_SFF_BIF1_R_N
R41  Q_RES  0 5% CHIP  pkg 0402LF  page 131 : 1 = OCP_SFF_ISO_BIF2_EN ; 2 = OCP_SFF_BIF2_R_N
R42  Q_RES  0 5% CHIP  pkg 0402LF  page 131 : 1 = USB2_P11_DN ; 2 = USB2_CPU0_P11_DN
R43  Q_RES  4.7K 5% EMPTY  pkg 0402LF  page 238 : 1 = P3V3_AUX ; 2 = SMB_FRU_3V3AUX_R1_SDA
R44  Q_RES  1K 1% CHIP  pkg 0402LF  page 238 : 1 = PD_CPU_FRU_WP ; 2 = GND
R45  Q_RES  10K 1% CHIP  pkg 0402LF  page 133 : 1 = P3V3_OCP_SFF ; 2 = PU_OCP_SFF_WAKE_OE
R46  Q_RES  0 5% CHIP  pkg 0402LF  page 131 : 1 = USB2_P11_DP ; 2 = USB2_CPU0_P11_DP
R47  Q_RES  200 1% CHIP  pkg 0402LF  page 131 : 1 = SMB_OCP_SFF_3V3AUX_BUF_R_SCL ; 2 = SMB_OCP_SFF_3V3AUX_BUF_SCL
R48  Q_RES  200 1% CHIP  pkg 0402LF  page 131 : 1 = SMB_OCP_SFF_3V3AUX_BUF_R_SDA ; 2 = SMB_OCP_SFF_3V3AUX_BUF_SDA
R49  Q_RES  33 5% CHIP  pkg 0402LF  page 80 : 1 = SCM_JTAG_MUX_R_S0 ; 2 = SCM_JTAG_MUX_S0
R50  Q_RES  33 5% CHIP  pkg 0402LF  page 80 : 1 = SCM_JTAG_MUX_R_S1 ; 2 = SCM_JTAG_MUX_S1
R51  Q_RES  0 5% CHIP  pkg 0402LF  page 80 : 1 = SMB_1_PLD_3V3AUX_SCL_R1 ; 2 = SMB_1_PLD_3V3AUX_SCL_R2
R52  Q_RES  10K 1% EMPTY  pkg 0402LF  page 238 : 1 = P3V3_AUX ; 2 = CPU_FRU_ADDR2
R53  Q_RES  4.7K 1% CHIP  pkg 0402LF  page 133 : 1 = P3V3_AUX ; 2 = OCP_SFF_PWRBRK_BUFF_N
R54  Q_RES  1K 1% CHIP  pkg 0402LF  page 238 : 1 = CPU_FRU_ADDR2 ; 2 = GND
R55  Q_RES  33.2 1% CHIP  pkg 0402LF  page 250 : 1 = SMB_PCIE0_3V3AUX_SDA ; 2 = SMB_PCIE0_3V3AUX_SDA_R
R56  Q_RES  0 5% CHIP  pkg 0402LF  page 80 : 1 = SMB_1_PLD_3V3AUX_SDA_R1 ; 2 = SMB_1_PLD_3V3AUX_SDA_R2
R57  Q_RES  0 5% CHIP  pkg 0402LF  page 81 : 1 = RST_CPU1_RESETL_N ; 2 = FM_RST_CPU1_RESETL_N
R58  Q_RES  33 5% CHIP  pkg 0402LF  page 80 : 1 = SGPIO_SCM_INTR_R_N ; 2 = SGPIO_SCM_INTR_N
R59  Q_RES  22 1% CHIP  pkg 0402LF  page 132 : 1 = NCSI_BMC_CRS_DV_R ; 2 = RMII_OCP_BMC_CRSDV
R60  Q_RES  10K 1% EMPTY  pkg 0402LF  page 238 : 1 = P3V3_AUX ; 2 = CPU_FRU_ADDR1
R61  Q_RES  49.9 1% CHIP  pkg 0402LF  page 200 : 1 = SVID_PVDDCR_CPU1_P0_SVTO ; 2 = SVID_PVDDCR_CPU1_P0_SVTO_R
R62  Q_RES  1K 1% CHIP  pkg 0402LF  page 238 : 1 = CPU_FRU_ADDR1 ; 2 = GND
R63  Q_RES  33 5% CHIP  pkg 0402LF  page 80 : 1 = SCM_SYS_PWROK_R ; 2 = SCM_SYS_PWROK
R64  Q_RES  1K 1% EMPTY  pkg 0402LF  page 83 : 1 = SCM_SYS_PWRBTN_N ; 2 = P3V3_AUX
R65  Q_RES  33.2 1% CHIP  pkg 0402LF  page 250 : 1 = SMB_PCIE0_3V3AUX_SCL ; 2 = SMB_PCIE0_3V3AUX_SCL_R
R66  Q_RES  2.2K 5% CHIP  pkg 0402LF  page 250 : 1 = P3V3_AUX ; 2 = SMB_FRU_3V3AUX_SCL
R67  Q_RES  2.2K 5% CHIP  pkg 0402LF  page 250 : 1 = P3V3_AUX ; 2 = SMB_FRU_3V3AUX_SDA
R68  Q_RES  1K 1% EMPTY  pkg 0402LF  page 238 : 1 = P3V3_AUX ; 2 = CPU_FRU_ADDR0
R69  Q_RES  10K 1% CHIP  pkg 0402LF  page 238 : 1 = CPU_FRU_ADDR0 ; 2 = GND
R70  Q_RES  0 5% CHIP  pkg 0402LF  page 80 : 1 = SMB_CPU0_4_XLTR_R_SCL ; 2 = SMB_CPU0_4_XLTR_SCL
R71  Q_RES  33 5% CHIP  pkg 0402LF  page 84 : 1 = SCM_IRQ_R_N ; 2 = SCM_IRQ_N
R72  Q_RES  22 1% CHIP  pkg 0402LF  page 132 : 1 = NCSI_BMC_RXD0_R ; 2 = RMII_OCP_BMC_RXD_0
R73  Q_RES  22 1% CHIP  pkg 0402LF  page 132 : 1 = NCSI_BMC_RXD1_R ; 2 = RMII_OCP_BMC_RXD_1
R74  Q_RES  0 5% CHIP  pkg 0402LF  page 132 : 1 = NCSI_BMC_TX_EN_R ; 2 = RMII_BMC_OCP_TX_EN
R75  Q_RES  0 5% CHIP  pkg 0402LF  page 132 : 1 = NCSI_BMC_TXD0_R ; 2 = RMII_BMC_OCP_TXD_0
R76  Q_RES  0 5% CHIP  pkg 0402LF  page 132 : 1 = NCSI_BMC_TXD1_R ; 2 = RMII_BMC_OCP_TXD_1
R77  Q_RES  100K 1% CHIP  pkg 0402LF  page 132 : 1 = RMII_OCP_BMC_CRSDV ; 2 = GND
R78  Q_RES  4.7K 5% EMPTY  pkg 0402LF  page 160 : 1 = P3V3 ; 2 = PU_U5_EN
R79  Q_RES  100K 1% CHIP  pkg 0402LF  page 132 : 1 = RMII_OCP_BMC_RXD_0 ; 2 = GND
R80  Q_RES  100K 1% CHIP  pkg 0402LF  page 132 : 1 = RMII_OCP_BMC_RXD_1 ; 2 = GND
R81  Q_RES  33 5% CHIP  pkg 0402LF  page 82 : 1 = FM_INT_CPU0_HP_UBM_R_N ; 2 = FM_INT_CPU0_HP_UBM_N
R82  Q_RES  100K 1% CHIP  pkg 0402LF  page 132 : 1 = RMII_BMC_OCP_TX_EN ; 2 = GND
R83  Q_RES  100K 1% CHIP  pkg 0402LF  page 132 : 1 = RMII_BMC_OCP_TXD_0 ; 2 = GND
R84  Q_RES  100K 1% CHIP  pkg 0402LF  page 132 : 1 = RMII_BMC_OCP_TXD_1 ; 2 = GND
R85  Q_RES  0 5% CHIP  pkg 0402LF  page 238 : 1 = SMB_FRU_3V3AUX_SCL ; 2 = SMB_FRU_3V3AUX_R1_SCL
R86  Q_RES  0 5% CHIP  pkg 0402LF  page 238 : 1 = SMB_FRU_3V3AUX_SDA ; 2 = SMB_FRU_3V3AUX_R1_SDA
R87  Q_RES  1K 1% CHIP  pkg 0402LF  page 132 : 1 = RMII_BMC_OCP_RX_ER ; 2 = GND
R88  Q_RES  1K 1% EMPTY  pkg 0402LF  page 86 : 1 = P3V3 ; 2 = PWRGD_CHAF_CPU0
R89  Q_RES  1K 1% EMPTY  pkg 0402LF  page 86 : 1 = P3V3 ; 2 = PWRGD_CHA_CPU0_DIMM0
R90  Q_RES  1K 1% EMPTY  pkg 0402LF  page 87 : 1 = P3V3 ; 2 = PWRGD_CHB_CPU0_DIMM
R91  Q_RES  1K 1% EMPTY  pkg 0402LF  page 88 : 1 = P3V3 ; 2 = PWRGD_CHC_CPU0_DIMM
R92  Q_RES  1K 1% EMPTY  pkg 0402LF  page 89 : 1 = P3V3 ; 2 = PWRGD_CHD_CPU0_DIMM
R93  Q_RES  1K 1% EMPTY  pkg 0402LF  page 90 : 1 = P3V3 ; 2 = PWRGD_CHE_CPU0_DIMM
R94  Q_RES  1K 1% EMPTY  pkg 0402LF  page 91 : 1 = P3V3 ; 2 = PWRGD_CHF_CPU0_DIMM
R95  Q_RES  1K 1% EMPTY  pkg 0402LF  page 92 : 1 = P3V3 ; 2 = PWRGD_CHGL_CPU0
R96  Q_RES  1K 1% EMPTY  pkg 0402LF  page 92 : 1 = P3V3 ; 2 = PWRGD_CHG_CPU0_DIMM0
R97  Q_RES  1K 1% EMPTY  pkg 0402LF  page 93 : 1 = P3V3 ; 2 = PWRGD_CHH_CPU0_DIMM
R98  Q_RES  1K 1% EMPTY  pkg 0402LF  page 94 : 1 = P3V3 ; 2 = PWRGD_CHI_CPU0_DIMM
R99  Q_RES  1K 1% EMPTY  pkg 0402LF  page 95 : 1 = P3V3 ; 2 = PWRGD_CHJ_CPU0_DIMM
R100  Q_RES  1K 1% EMPTY  pkg 0402LF  page 96 : 1 = P3V3 ; 2 = PWRGD_CHK_CPU0_DIMM
R101  Q_RES  1K 1% EMPTY  pkg 0402LF  page 97 : 1 = P3V3 ; 2 = PWRGD_CHL_CPU0_DIMM
R102  Q_RES  1K 1% EMPTY  pkg 0402LF  page 98 : 1 = P3V3 ; 2 = PWRGD_CHAF_CPU1
R103  Q_RES  1K 1% EMPTY  pkg 0402LF  page 98 : 1 = P3V3 ; 2 = PWRGD_CHA_CPU1_DIMM0
R104  Q_RES  1K 1% EMPTY  pkg 0402LF  page 99 : 1 = P3V3 ; 2 = PWRGD_CHB_CPU1_DIMM
R105  Q_RES  1K 1% EMPTY  pkg 0402LF  page 100 : 1 = P3V3 ; 2 = PWRGD_CHC_CPU1_DIMM
R106  Q_RES  1K 1% EMPTY  pkg 0402LF  page 101 : 1 = P3V3 ; 2 = PWRGD_CHD_CPU1_DIMM
R107  Q_RES  1K 1% EMPTY  pkg 0402LF  page 102 : 1 = P3V3 ; 2 = PWRGD_CHE_CPU1_DIMM
R108  Q_RES  1K 1% EMPTY  pkg 0402LF  page 103 : 1 = P3V3 ; 2 = PWRGD_CHF_CPU1_DIMM
R109  Q_RES  1K 1% EMPTY  pkg 0402LF  page 104 : 1 = P3V3 ; 2 = PWRGD_CHGL_CPU1
R110  Q_RES  1K 1% EMPTY  pkg 0402LF  page 104 : 1 = P3V3 ; 2 = PWRGD_CHG_CPU1_DIMM0
R111  Q_RES  1K 1% EMPTY  pkg 0402LF  page 105 : 1 = P3V3 ; 2 = PWRGD_CHH_CPU1_DIMM
R112  Q_RES  1K 1% EMPTY  pkg 0402LF  page 106 : 1 = P3V3 ; 2 = PWRGD_CHI_CPU1_DIMM
R113  Q_RES  1K 1% EMPTY  pkg 0402LF  page 107 : 1 = P3V3 ; 2 = PWRGD_CHJ_CPU1_DIMM
R114  Q_RES  1K 1% EMPTY  pkg 0402LF  page 108 : 1 = P3V3 ; 2 = PWRGD_CHK_CPU1_DIMM
R115  Q_RES  1K 1% EMPTY  pkg 0402LF  page 109 : 1 = P3V3 ; 2 = PWRGD_CHL_CPU1_DIMM
R116  Q_RES  33 5% CHIP  pkg 0402LF  page 155 : 1 = IRQ_OCP_SFF_WAKE_BUF_N ; 2 = IRQ_LVC3_WAKE_N
R117  Q_RES  1K 1% CHIP  pkg 0402LF  page 207 : 1 = P3V3_AUX ; 2 = PWRGD_PVDD11_S3_P0_R
R118  Q_RES  0 5% CHIP  pkg 0402LF  page 207 : 1 = SMB_SCM_2_R6_SCL ; 2 = PVDD11_S3_P0_PMSCL_R
R119  Q_RES  0 5% CHIP  pkg 0402LF  page 207 : 1 = SMB_SCM_2_R6_SDA ; 2 = PVDD11_S3_P0_PMSDA_R
R120  Q_RES  33 5% CHIP  pkg 0402LF  page 207 : 1 = PVDD11_S3_P0_PMALERT ; 2 = PVDD11_S3_P0_PMALERT_R
R121  Q_RES  0 5% CHIP  pkg 0402LF  page 238 : 1 = SMB_FRU_3V3AUX_SCL ; 2 = SMB_CPU_FRU_3V3AUX_SCL
R122  Q_RES  0 5% CHIP  pkg 0402LF  page 207 : 1 = PWRGD_PVDD11_S3_P0 ; 2 = PWRGD_PVDD11_S3_P0_R
R123  Q_RES  0 5% CHIP  pkg 0402LF  page 207 : 1 = PVDD11_S3_P0_EN ; 2 = PVDD11_S3_P0_EN_R
R124  Q_RES  1K 1% EMPTY  pkg 0402LF  page 207 : 1 = PVDD18_S5_P0 ; 2 = PVDD11_S3_P0_OCP_N_R
R125  Q_RES  0 5% CHIP  pkg 0402LF  page 238 : 1 = SMB_FRU_3V3AUX_SDA ; 2 = SMB_CPU_FRU_3V3AUX_SDA
R126  Q_RES  10K 1% CHIP  pkg 0402LF  page 83 : 1 = FM_APML_MUX2_OE_N ; 2 = GND
R127  Q_RES  1K 1% EMPTY  pkg 0402LF  page 77 : 1 = P3V3_AUX ; 2 = SPI_CPU0_LVC3_SCM_D1
R128  Q_RES  1K 1% EMPTY  pkg 0402LF  page 77 : 1 = P3V3_AUX ; 2 = SPI_CPU0_LVC3_SCM_D2
R129  Q_RES  1K 1% EMPTY  pkg 0402LF  page 77 : 1 = P3V3_AUX ; 2 = SPI_CPU0_LVC3_SCM_D3
R130  Q_RES  10K 5% EMPTY  pkg 0402LF  page 151 : 1 = UART_VCC_J8 ; 2 = P5V_AUX
R131  Q_RES  10K 5% CHIP  pkg 0402LF  page 151 : 1 = P3V3_AUX ; 2 = UART_VCC_J8
R132  Q_RES  0 5% CHIP  pkg 0402LF  page 82 : 1 = FM_APML_MUX2_OE_N ; 2 = FM_APML_MUX2_OE_R_N
R133  Q_RES  0 5% CHIP  pkg 0402LF  page 82 : 1 = FM_APML_MUX2_SEL ; 2 = FM_APML_MUX2_SEL_R
R134  Q_RES  4.7K 5% EMPTY  pkg 0402LF  page 83 : 1 = FM_APML_MUX2_OE_N ; 2 = P3V3_AUX
R135  Q_RES  4.7K 5% EMPTY  pkg 0402LF  page 83 : 1 = FM_APML_MUX2_SEL ; 2 = P3V3_AUX
R136  Q_RES  10K 1% EMPTY  pkg 0402LF  page 83 : 1 = FM_APML_MUX2_SEL ; 2 = GND
R137  Q_RES  0 5% CHIP  pkg 0402LF  page 82 : 1 = PVDDCR_CPU1_P0_OCP_N ; 2 = FM_PVDDCR_CPU1_P0_OCP_N
R138  Q_RES  4.7K 1% EMPTY  pkg 0402LF  page 144 : 1 = M2_SSD0_CLKREQ_EN_N ; 2 = GND
R139  Q_RES  0 5% EMPTY  pkg 0402LF  page 161 : 1 = I3C_MUX_CPU0_VIO ; 2 = PVDD18_S5_P0
R140  Q_RES  0 5% EMPTY  pkg 0402LF  page 160 : 1 = SMB_CPU0_CPU1_APML_SCL ; 2 = SMB_CPU0_CPU1_APML_BUF1_SCL
R141  Q_RES  0 5% CHIP  pkg 0402LF  page 82 : 1 = PVDDCR_CPU1_P1_OCP_N ; 2 = FM_PVDDCR_CPU1_P1_OCP_N
R142  Q_RES  0 5% EMPTY  pkg 0402LF  page 161 : 1 = SMB_CPU0_CPU1_APML_MUX1_SCL ; 2 = SMB_APML_CPU0_R_SCL
R143  Q_RES  0 5% EMPTY  pkg 0402LF  page 161 : 1 = SMB_CPU0_CPU1_APML_MUX1_SDA ; 2 = SMB_APML_CPU0_R_SDA
R144  Q_RES  0 5% EMPTY  pkg 0402LF  page 161 : 1 = SMB_CPU0_CPU1_SEC_SDA_R2 ; 2 = SMB_CPU0_SEC_R_SDA
R145  Q_RES  0 5% EMPTY  pkg 0402LF  page 161 : 1 = SMB_CPU0_CPU1_SEC_SCL_R2 ; 2 = SMB_CPU0_SEC_R_SCL
R146  Q_RES  0 5% EMPTY  pkg 0402LF  page 161 : 1 = SMB_CPU0_CPU1_APML_MUX1_SCL ; 2 = SMB_APML_CPU1_R_SCL
R147  Q_RES  0 5% EMPTY  pkg 0402LF  page 161 : 1 = SMB_CPU0_CPU1_APML_MUX1_SDA ; 2 = SMB_APML_CPU1_R_SDA
R148  Q_RES  0 5% EMPTY  pkg 0402LF  page 161 : 1 = SMB_CPU0_CPU1_SEC_SDA_R2 ; 2 = SMB_CPU1_SEC_R_SDA
R149  Q_RES  0 5% CHIP  pkg 0402LF  page 210 : 1 = PVDDCR_SOC_P1_EN ; 2 = PVDDCR_SOC_P1_EN_RC
R150  Q_RES  0 5% EMPTY  pkg 0402LF  page 160 : 1 = SMB_CPU0_CPU1_APML_SDA ; 2 = SMB_CPU0_CPU1_APML_BUF1_SDA
R151  Q_RES  0 5% CHIP  pkg 0402LF  page 160 : 1 = SMB_CPU0_CPU1_APML_SCL ; 2 = SMB_CPU0_CPU1_APML_BUF2_SCL
R152  Q_RES  33 5% CHIP  pkg 0402LF  page 80 : 1 = P12V_OCP_SFF_EN ; 2 = P12V_OCP_SFF_EN_R
R153  Q_RES  0 5% CHIP  pkg 0402LF  page 144 : 1 = M2_SSD0_CLKREQ_EN_N ; 2 = M2_SSD0_CLKREQ_EN_N_BUF
R154  Q_RES  1K 1% EMPTY  pkg 0402LF  page 210 : 1 = PVDD18_S5_P1 ; 2 = SVID_PVDDCR_CPU0_P1_SVTO
R155  Q_RES  1K 1% EMPTY  pkg 0402LF  page 144 : 1 = P3V3_AUX ; 2 = M2_SSD0_CLKREQ_EN_N_BUF
R156  Q_RES  0 5% CHIP  pkg 0402LF  page 27 : 1 = CPU0_XTRIG_R2_L4 ; 2 = CPU0_XTRIG_L4
R157  Q_RES  0 5% CHIP  pkg 0402LF  page 27 : 1 = CPU0_XTRIG_R2_L5 ; 2 = CPU0_XTRIG_L5
R158  Q_RES  33 5% CHIP  pkg 0402LF  page 81 : 1 = FM_PLD_CPU0_PRSNT_HDT ; 2 = CPU0_HDT_BYPASS_SEL
R159  Q_RES  33 5% CHIP  pkg 0402LF  page 81 : 1 = CPU0_JTAG_BUF_OE ; 2 = CPU0_JTAG_BUF_R_OE
R160  Q_RES  33 5% CHIP  pkg 0402LF  page 80 : 1 = JTAG_SCM_TRST_R_N ; 2 = JTAG_SCM_TRST_N
R161  Q_RES  33 5% CHIP  pkg 0402LF  page 81 : 1 = CPU1_JTAG_BUF_R_OE ; 2 = CPU1_JTAG_BUF_OE
